G04 ================== begin FILE IDENTIFICATION RECORD ==================*
G04 Layout Name:  12433-1M.brd*
G04 Film Name:    TMASK*
G04 File Format:  Gerber RS274X*
G04 File Origin:  Cadence Allegro 16.2-S037*
G04 Origin Date:  Fri Dec 07 18:55:06 2012*
G04 *
G04 Layer:  VIA CLASS/SOLDERMASK_TOP*
G04 Layer:  PIN/SOLDERMASK_TOP*
G04 Layer:  PACKAGE GEOMETRY/SOLDERMASK_TOP*
G04 Layer:  DRAWING FORMAT/LAYER_PCB_STORY*
G04 Layer:  DRAWING FORMAT/LAYER_SOLDER_T*
G04 Layer:  BOARD GEOMETRY/SOLDERMASK_TOP*
G04 *
G04 Offset:    (0.00 0.00)*
G04 Mirror:    No*
G04 Mode:      Positive*
G04 Rotation:  0*
G04 FullContactRelief:  No*
G04 UndefLineWidth:     6.00*
G04 ================== end FILE IDENTIFICATION RECORD ====================*
%FSLAX35Y35*MOIN*%
%IR0*IPPOS*OFA0.00000B0.00000*MIA0B0*SFA1.00000B1.00000*%
%AMMACRO47*
4,1,40,.013,.017,
-.013,.017,
-.013695,.016939,
-.014368,.016759,
-.015,.016464,
-.015571,.016064,
-.016064,.015571,
-.016464,.015,
-.016759,.014368,
-.016939,.013695,
-.017,.013,
-.017,-.013,
-.016939,-.013695,
-.016759,-.014368,
-.016464,-.015,
-.016064,-.015571,
-.015571,-.016064,
-.015,-.016464,
-.014368,-.016759,
-.013695,-.016939,
-.013,-.017,
.013,-.017,
.013695,-.016939,
.014368,-.016759,
.015,-.016464,
.015571,-.016064,
.016064,-.015571,
.016464,-.015,
.016759,-.014368,
.016939,-.013695,
.017,-.013,
.017,.013,
.016939,.013695,
.016759,.014368,
.016464,.015,
.016064,.015571,
.015571,.016064,
.015,.016464,
.014368,.016759,
.013695,.016939,
.013,.017,
0.0*
%
%ADD47MACRO47*%
%AMMACRO25*
4,1,40,.017,-.013,
.017,.013,
.016939,.013695,
.016759,.014368,
.016464,.015,
.016064,.015571,
.015571,.016064,
.015,.016464,
.014368,.016759,
.013695,.016939,
.013,.017,
-.013,.017,
-.013695,.016939,
-.014368,.016759,
-.015,.016464,
-.015571,.016064,
-.016064,.015571,
-.016464,.015,
-.016759,.014368,
-.016939,.013695,
-.017,.013,
-.017,-.013,
-.016939,-.013695,
-.016759,-.014368,
-.016464,-.015,
-.016064,-.015571,
-.015571,-.016064,
-.015,-.016464,
-.014368,-.016759,
-.013695,-.016939,
-.013,-.017,
.013,-.017,
.013695,-.016939,
.014368,-.016759,
.015,-.016464,
.015571,-.016064,
.016064,-.015571,
.016464,-.015,
.016759,-.014368,
.016939,-.013695,
.017,-.013,
0.0*
%
%ADD25MACRO25*%
%ADD29R,.08X.127*%
%ADD51C,.032*%
%ADD15C,.05*%
%ADD48R,.085X.128*%
%ADD18C,.028*%
%ADD54R,.208X.087*%
%ADD13C,.056*%
%ADD44C,.057*%
%ADD34R,.087X.208*%
%AMMACRO81*
4,1,40,-.014,-.008,
-.014,.008,
-.013939,.008695,
-.013759,.009368,
-.013464,.01,
-.013064,.010571,
-.012571,.011064,
-.012,.011464,
-.011368,.011759,
-.010695,.011939,
-.01,.012,
.01,.012,
.010695,.011939,
.011368,.011759,
.012,.011464,
.012571,.011064,
.013064,.010571,
.013464,.01,
.013759,.009368,
.013939,.008695,
.014,.008,
.014,-.008,
.013939,-.008695,
.013759,-.009368,
.013464,-.01,
.013064,-.010571,
.012571,-.011064,
.012,-.011464,
.011368,-.011759,
.010695,-.011939,
.01,-.012,
-.01,-.012,
-.010695,-.011939,
-.011368,-.011759,
-.012,-.011464,
-.012571,-.011064,
-.013064,-.010571,
-.013464,-.01,
-.013759,-.009368,
-.013939,-.008695,
-.014,-.008,
0.0*
%
%ADD81MACRO81*%
%AMMACRO75*
4,1,40,-.007,-.0225,
-.008389,-.022378,
-.009736,-.022018,
-.011,-.021428,
-.012142,-.020628,
-.013128,-.019642,
-.013928,-.0185,
-.014518,-.017236,
-.014878,-.015889,
-.015,-.0145,
-.015,.0145,
-.014878,.015889,
-.014518,.017236,
-.013928,.0185,
-.013128,.019642,
-.012142,.020628,
-.011,.021428,
-.009736,.022018,
-.008389,.022378,
-.007,.0225,
.007,.0225,
.008389,.022378,
.009736,.022018,
.011,.021428,
.012142,.020628,
.013128,.019642,
.013928,.0185,
.014518,.017236,
.014878,.015889,
.015,.0145,
.015,-.0145,
.014878,-.015889,
.014518,-.017236,
.013928,-.0185,
.013128,-.019642,
.012142,-.020628,
.011,-.021428,
.009736,-.022018,
.008389,-.022378,
.007,-.0225,
-.007,-.0225,
0.0*
%
%ADD75MACRO75*%
%ADD43C,.099*%
%AMMACRO37*
4,1,40,.011,-.007,
.011,.007,
.010939,.007695,
.010759,.008368,
.010464,.009,
.010064,.009571,
.009571,.010064,
.009,.010464,
.008368,.010759,
.007695,.010939,
.007,.011,
-.007,.011,
-.007695,.010939,
-.008368,.010759,
-.009,.010464,
-.009571,.010064,
-.010064,.009571,
-.010464,.009,
-.010759,.008368,
-.010939,.007695,
-.011,.007,
-.011,-.007,
-.010939,-.007695,
-.010759,-.008368,
-.010464,-.009,
-.010064,-.009571,
-.009571,-.010064,
-.009,-.010464,
-.008368,-.010759,
-.007695,-.010939,
-.007,-.011,
.007,-.011,
.007695,-.010939,
.008368,-.010759,
.009,-.010464,
.009571,-.010064,
.010064,-.009571,
.010464,-.009,
.010759,-.008368,
.010939,-.007695,
.011,-.007,
0.0*
%
%ADD37MACRO37*%
%AMMACRO23*
4,1,40,.007,.011,
-.007,.011,
-.007695,.010939,
-.008368,.010759,
-.009,.010464,
-.009571,.010064,
-.010064,.009571,
-.010464,.009,
-.010759,.008368,
-.010939,.007695,
-.011,.007,
-.011,-.007,
-.010939,-.007695,
-.010759,-.008368,
-.010464,-.009,
-.010064,-.009571,
-.009571,-.010064,
-.009,-.010464,
-.008368,-.010759,
-.007695,-.010939,
-.007,-.011,
.007,-.011,
.007695,-.010939,
.008368,-.010759,
.009,-.010464,
.009571,-.010064,
.010064,-.009571,
.010464,-.009,
.010759,-.008368,
.010939,-.007695,
.011,-.007,
.011,.007,
.010939,.007695,
.010759,.008368,
.010464,.009,
.010064,.009571,
.009571,.010064,
.009,.010464,
.008368,.010759,
.007695,.010939,
.007,.011,
0.0*
%
%ADD23MACRO23*%
%AMMACRO66*
4,1,40,-.012,.008,
-.012,-.008,
-.011939,-.008695,
-.011759,-.009368,
-.011464,-.01,
-.011064,-.010571,
-.010571,-.011064,
-.01,-.011464,
-.009368,-.011759,
-.008695,-.011939,
-.008,-.012,
.008,-.012,
.008695,-.011939,
.009368,-.011759,
.01,-.011464,
.010571,-.011064,
.011064,-.010571,
.011464,-.01,
.011759,-.009368,
.011939,-.008695,
.012,-.008,
.012,.008,
.011939,.008695,
.011759,.009368,
.011464,.01,
.011064,.010571,
.010571,.011064,
.01,.011464,
.009368,.011759,
.008695,.011939,
.008,.012,
-.008,.012,
-.008695,.011939,
-.009368,.011759,
-.01,.011464,
-.010571,.011064,
-.011064,.010571,
-.011464,.01,
-.011759,.009368,
-.011939,.008695,
-.012,.008,
0.0*
%
%ADD66MACRO66*%
%AMMACRO40*
4,1,40,.008,.012,
-.008,.012,
-.008695,.011939,
-.009368,.011759,
-.01,.011464,
-.010571,.011064,
-.011064,.010571,
-.011464,.01,
-.011759,.009368,
-.011939,.008695,
-.012,.008,
-.012,-.008,
-.011939,-.008695,
-.011759,-.009368,
-.011464,-.01,
-.011064,-.010571,
-.010571,-.011064,
-.01,-.011464,
-.009368,-.011759,
-.008695,-.011939,
-.008,-.012,
.008,-.012,
.008695,-.011939,
.009368,-.011759,
.01,-.011464,
.010571,-.011064,
.011064,-.010571,
.011464,-.01,
.011759,-.009368,
.011939,-.008695,
.012,-.008,
.012,.008,
.011939,.008695,
.011759,.009368,
.011464,.01,
.011064,.010571,
.010571,.011064,
.01,.011464,
.009368,.011759,
.008695,.011939,
.008,.012,
0.0*
%
%ADD40MACRO40*%
%AMMACRO36*
4,1,40,-.013,-.017,
.013,-.017,
.013695,-.016939,
.014368,-.016759,
.015,-.016464,
.015571,-.016064,
.016064,-.015571,
.016464,-.015,
.016759,-.014368,
.016939,-.013695,
.017,-.013,
.017,.013,
.016939,.013695,
.016759,.014368,
.016464,.015,
.016064,.015571,
.015571,.016064,
.015,.016464,
.014368,.016759,
.013695,.016939,
.013,.017,
-.013,.017,
-.013695,.016939,
-.014368,.016759,
-.015,.016464,
-.015571,.016064,
-.016064,.015571,
-.016464,.015,
-.016759,.014368,
-.016939,.013695,
-.017,.013,
-.017,-.013,
-.016939,-.013695,
-.016759,-.014368,
-.016464,-.015,
-.016064,-.015571,
-.015571,-.016064,
-.015,-.016464,
-.014368,-.016759,
-.013695,-.016939,
-.013,-.017,
0.0*
%
%ADD36MACRO36*%
%AMMACRO45*
4,1,40,-.017,.013,
-.017,-.013,
-.016939,-.013695,
-.016759,-.014368,
-.016464,-.015,
-.016064,-.015571,
-.015571,-.016064,
-.015,-.016464,
-.014368,-.016759,
-.013695,-.016939,
-.013,-.017,
.013,-.017,
.013695,-.016939,
.014368,-.016759,
.015,-.016464,
.015571,-.016064,
.016064,-.015571,
.016464,-.015,
.016759,-.014368,
.016939,-.013695,
.017,-.013,
.017,.013,
.016939,.013695,
.016759,.014368,
.016464,.015,
.016064,.015571,
.015571,.016064,
.015,.016464,
.014368,.016759,
.013695,.016939,
.013,.017,
-.013,.017,
-.013695,.016939,
-.014368,.016759,
-.015,.016464,
-.015571,.016064,
-.016064,.015571,
-.016464,.015,
-.016759,.014368,
-.016939,.013695,
-.017,.013,
0.0*
%
%ADD45MACRO45*%
%AMMACRO85*
4,1,25,-.26969,-.01299,
-.26969,-.83465,
.26969,-.83465,
.26969,.83465,
-.26969,.83465,
-.26969,.12087,
-.22638,.12087,
-.214758,.119853,
-.203489,.116834,
-.192915,.111903,
-.183358,.105211,
-.175109,.096962,
-.168417,.087405,
-.163486,.076831,
-.160467,.065562,
-.15945,.05394,
-.160467,.042318,
-.163486,.031049,
-.168417,.020475,
-.175109,.010918,
-.183358,.002669,
-.192915,-.004023,
-.203489,-.008954,
-.214758,-.011973,
-.22638,-.01299,
-.26969,-.01299,
0.0*
%
%ADD85MACRO85*%
%AMMACRO38*
4,1,40,.011,-.007,
.011,.007,
.010939,.007695,
.010759,.008368,
.010464,.009,
.010064,.009571,
.009571,.010064,
.009,.010464,
.008368,.010759,
.007695,.010939,
.007,.011,
-.007,.011,
-.007695,.010939,
-.008368,.010759,
-.009,.010464,
-.009571,.010064,
-.010064,.009571,
-.010464,.009,
-.010759,.008368,
-.010939,.007695,
-.011,.007,
-.011,-.007,
-.010939,-.007695,
-.010759,-.008368,
-.010464,-.009,
-.010064,-.009571,
-.009571,-.010064,
-.009,-.010464,
-.008368,-.010759,
-.007695,-.010939,
-.007,-.011,
.007,-.011,
.007695,-.010939,
.008368,-.010759,
.009,-.010464,
.009571,-.010064,
.010064,-.009571,
.010464,-.009,
.010759,-.008368,
.010939,-.007695,
.011,-.007,
0.0*
%
%ADD38MACRO38*%
%AMMACRO26*
4,1,40,.007,.011,
-.007,.011,
-.007695,.010939,
-.008368,.010759,
-.009,.010464,
-.009571,.010064,
-.010064,.009571,
-.010464,.009,
-.010759,.008368,
-.010939,.007695,
-.011,.007,
-.011,-.007,
-.010939,-.007695,
-.010759,-.008368,
-.010464,-.009,
-.010064,-.009571,
-.009571,-.010064,
-.009,-.010464,
-.008368,-.010759,
-.007695,-.010939,
-.007,-.011,
.007,-.011,
.007695,-.010939,
.008368,-.010759,
.009,-.010464,
.009571,-.010064,
.010064,-.009571,
.010464,-.009,
.010759,-.008368,
.010939,-.007695,
.011,-.007,
.011,.007,
.010939,.007695,
.010759,.008368,
.010464,.009,
.010064,.009571,
.009571,.010064,
.009,.010464,
.008368,.010759,
.007695,.010939,
.007,.011,
0.0*
%
%ADD26MACRO26*%
%AMMACRO65*
4,1,40,-.012,.008,
-.012,-.008,
-.011939,-.008695,
-.011759,-.009368,
-.011464,-.01,
-.011064,-.010571,
-.010571,-.011064,
-.01,-.011464,
-.009368,-.011759,
-.008695,-.011939,
-.008,-.012,
.008,-.012,
.008695,-.011939,
.009368,-.011759,
.01,-.011464,
.010571,-.011064,
.011064,-.010571,
.011464,-.01,
.011759,-.009368,
.011939,-.008695,
.012,-.008,
.012,.008,
.011939,.008695,
.011759,.009368,
.011464,.01,
.011064,.010571,
.010571,.011064,
.01,.011464,
.009368,.011759,
.008695,.011939,
.008,.012,
-.008,.012,
-.008695,.011939,
-.009368,.011759,
-.01,.011464,
-.010571,.011064,
-.011064,.010571,
-.011464,.01,
-.011759,.009368,
-.011939,.008695,
-.012,.008,
0.0*
%
%ADD65MACRO65*%
%AMMACRO39*
4,1,40,.008,.012,
-.008,.012,
-.008695,.011939,
-.009368,.011759,
-.01,.011464,
-.010571,.011064,
-.011064,.010571,
-.011464,.01,
-.011759,.009368,
-.011939,.008695,
-.012,.008,
-.012,-.008,
-.011939,-.008695,
-.011759,-.009368,
-.011464,-.01,
-.011064,-.010571,
-.010571,-.011064,
-.01,-.011464,
-.009368,-.011759,
-.008695,-.011939,
-.008,-.012,
.008,-.012,
.008695,-.011939,
.009368,-.011759,
.01,-.011464,
.010571,-.011064,
.011064,-.010571,
.011464,-.01,
.011759,-.009368,
.011939,-.008695,
.012,-.008,
.012,.008,
.011939,.008695,
.011759,.009368,
.011464,.01,
.011064,.010571,
.010571,.011064,
.01,.011464,
.009368,.011759,
.008695,.011939,
.008,.012,
0.0*
%
%ADD39MACRO39*%
%AMMACRO30*
4,1,40,-.013,-.017,
.013,-.017,
.013695,-.016939,
.014368,-.016759,
.015,-.016464,
.015571,-.016064,
.016064,-.015571,
.016464,-.015,
.016759,-.014368,
.016939,-.013695,
.017,-.013,
.017,.013,
.016939,.013695,
.016759,.014368,
.016464,.015,
.016064,.015571,
.015571,.016064,
.015,.016464,
.014368,.016759,
.013695,.016939,
.013,.017,
-.013,.017,
-.013695,.016939,
-.014368,.016759,
-.015,.016464,
-.015571,.016064,
-.016064,.015571,
-.016464,.015,
-.016759,.014368,
-.016939,.013695,
-.017,.013,
-.017,-.013,
-.016939,-.013695,
-.016759,-.014368,
-.016464,-.015,
-.016064,-.015571,
-.015571,-.016064,
-.015,-.016464,
-.014368,-.016759,
-.013695,-.016939,
-.013,-.017,
0.0*
%
%ADD30MACRO30*%
%AMMACRO46*
4,1,40,-.017,.013,
-.017,-.013,
-.016939,-.013695,
-.016759,-.014368,
-.016464,-.015,
-.016064,-.015571,
-.015571,-.016064,
-.015,-.016464,
-.014368,-.016759,
-.013695,-.016939,
-.013,-.017,
.013,-.017,
.013695,-.016939,
.014368,-.016759,
.015,-.016464,
.015571,-.016064,
.016064,-.015571,
.016464,-.015,
.016759,-.014368,
.016939,-.013695,
.017,-.013,
.017,.013,
.016939,.013695,
.016759,.014368,
.016464,.015,
.016064,.015571,
.015571,.016064,
.015,.016464,
.014368,.016759,
.013695,.016939,
.013,.017,
-.013,.017,
-.013695,.016939,
-.014368,.016759,
-.015,.016464,
-.015571,.016064,
-.016064,.015571,
-.016464,.015,
-.016759,.014368,
-.016939,.013695,
-.017,.013,
0.0*
%
%ADD46MACRO46*%
%ADD50R,.135X.101*%
%ADD84R,.022X.04*%
%ADD59R,.04X.023*%
%ADD69R,.06X.012*%
%ADD68R,.012X.06*%
%ADD74R,.04X.016*%
%ADD73R,.014X.06*%
%ADD27R,.045X.03*%
%ADD16R,.03X.045*%
%ADD82R,.03X.046*%
%ADD49R,.03X.064*%
%ADD10C,.14*%
%ADD77R,.045X.016*%
%ADD76R,.016X.045*%
%ADD72R,.08X.071*%
%ADD41C,.115*%
%ADD17R,.05X.065*%
%ADD12C,.142*%
%ADD57R,.065X.05*%
%ADD80R,.071X.063*%
%ADD71R,.065X.025*%
%ADD42C,.126*%
%ADD31R,.055X.035*%
%ADD14C,.315*%
%ADD79R,.12X.12*%
%ADD63R,.09X.045*%
%ADD61R,.045X.055*%
%ADD60R,.035X.055*%
%ADD56R,.048X.016*%
%ADD70R,.055X.045*%
%ADD55R,.016X.048*%
%ADD78R,.122X.122*%
%ADD22R,.09X.095*%
%ADD11R,.16X.16*%
%AMMACRO83*
4,1,40,.007,.0225,
.008389,.022378,
.009736,.022018,
.011,.021428,
.012142,.020628,
.013128,.019642,
.013928,.0185,
.014518,.017236,
.014878,.015889,
.015,.0145,
.015,-.0145,
.014878,-.015889,
.014518,-.017236,
.013928,-.0185,
.013128,-.019642,
.012142,-.020628,
.011,-.021428,
.009736,-.022018,
.008389,-.022378,
.007,-.0225,
-.007,-.0225,
-.008389,-.022378,
-.009736,-.022018,
-.011,-.021428,
-.012142,-.020628,
-.013128,-.019642,
-.013928,-.0185,
-.014518,-.017236,
-.014878,-.015889,
-.015,-.0145,
-.015,.0145,
-.014878,.015889,
-.014518,.017236,
-.013928,.0185,
-.013128,.019642,
-.012142,.020628,
-.011,.021428,
-.009736,.022018,
-.008389,.022378,
-.007,.0225,
.007,.0225,
0.0*
%
%ADD83MACRO83*%
%ADD67C,.375*%
%ADD62R,.095X.09*%
%ADD58R,.059X.089*%
%AMMACRO53*
4,1,40,-.008,-.012,
.008,-.012,
.008695,-.011939,
.009368,-.011759,
.01,-.011464,
.010571,-.011064,
.011064,-.010571,
.011464,-.01,
.011759,-.009368,
.011939,-.008695,
.012,-.008,
.012,.008,
.011939,.008695,
.011759,.009368,
.011464,.01,
.011064,.010571,
.010571,.011064,
.01,.011464,
.009368,.011759,
.008695,.011939,
.008,.012,
-.008,.012,
-.008695,.011939,
-.009368,.011759,
-.01,.011464,
-.010571,.011064,
-.011064,.010571,
-.011464,.01,
-.011759,.009368,
-.011939,.008695,
-.012,.008,
-.012,-.008,
-.011939,-.008695,
-.011759,-.009368,
-.011464,-.01,
-.011064,-.010571,
-.010571,-.011064,
-.01,-.011464,
-.009368,-.011759,
-.008695,-.011939,
-.008,-.012,
0.0*
%
%ADD53MACRO53*%
%AMMACRO33*
4,1,40,.012,-.008,
.012,.008,
.011939,.008695,
.011759,.009368,
.011464,.01,
.011064,.010571,
.010571,.011064,
.01,.011464,
.009368,.011759,
.008695,.011939,
.008,.012,
-.008,.012,
-.008695,.011939,
-.009368,.011759,
-.01,.011464,
-.010571,.011064,
-.011064,.010571,
-.011464,.01,
-.011759,.009368,
-.011939,.008695,
-.012,.008,
-.012,-.008,
-.011939,-.008695,
-.011759,-.009368,
-.011464,-.01,
-.011064,-.010571,
-.010571,-.011064,
-.01,-.011464,
-.009368,-.011759,
-.008695,-.011939,
-.008,-.012,
.008,-.012,
.008695,-.011939,
.009368,-.011759,
.01,-.011464,
.010571,-.011064,
.011064,-.010571,
.011464,-.01,
.011759,-.009368,
.011939,-.008695,
.012,-.008,
0.0*
%
%ADD33MACRO33*%
%AMMACRO28*
4,1,40,-.007,-.011,
.007,-.011,
.007695,-.010939,
.008368,-.010759,
.009,-.010464,
.009571,-.010064,
.010064,-.009571,
.010464,-.009,
.010759,-.008368,
.010939,-.007695,
.011,-.007,
.011,.007,
.010939,.007695,
.010759,.008368,
.010464,.009,
.010064,.009571,
.009571,.010064,
.009,.010464,
.008368,.010759,
.007695,.010939,
.007,.011,
-.007,.011,
-.007695,.010939,
-.008368,.010759,
-.009,.010464,
-.009571,.010064,
-.010064,.009571,
-.010464,.009,
-.010759,.008368,
-.010939,.007695,
-.011,.007,
-.011,-.007,
-.010939,-.007695,
-.010759,-.008368,
-.010464,-.009,
-.010064,-.009571,
-.009571,-.010064,
-.009,-.010464,
-.008368,-.010759,
-.007695,-.010939,
-.007,-.011,
0.0*
%
%ADD28MACRO28*%
%AMMACRO19*
4,1,40,-.011,.007,
-.011,-.007,
-.010939,-.007695,
-.010759,-.008368,
-.010464,-.009,
-.010064,-.009571,
-.009571,-.010064,
-.009,-.010464,
-.008368,-.010759,
-.007695,-.010939,
-.007,-.011,
.007,-.011,
.007695,-.010939,
.008368,-.010759,
.009,-.010464,
.009571,-.010064,
.010064,-.009571,
.010464,-.009,
.010759,-.008368,
.010939,-.007695,
.011,-.007,
.011,.007,
.010939,.007695,
.010759,.008368,
.010464,.009,
.010064,.009571,
.009571,.010064,
.009,.010464,
.008368,.010759,
.007695,.010939,
.007,.011,
-.007,.011,
-.007695,.010939,
-.008368,.010759,
-.009,.010464,
-.009571,.010064,
-.010064,.009571,
-.010464,.009,
-.010759,.008368,
-.010939,.007695,
-.011,.007,
0.0*
%
%ADD19MACRO19*%
%AMMACRO35*
4,1,40,.013,.017,
-.013,.017,
-.013695,.016939,
-.014368,.016759,
-.015,.016464,
-.015571,.016064,
-.016064,.015571,
-.016464,.015,
-.016759,.014368,
-.016939,.013695,
-.017,.013,
-.017,-.013,
-.016939,-.013695,
-.016759,-.014368,
-.016464,-.015,
-.016064,-.015571,
-.015571,-.016064,
-.015,-.016464,
-.014368,-.016759,
-.013695,-.016939,
-.013,-.017,
.013,-.017,
.013695,-.016939,
.014368,-.016759,
.015,-.016464,
.015571,-.016064,
.016064,-.015571,
.016464,-.015,
.016759,-.014368,
.016939,-.013695,
.017,-.013,
.017,.013,
.016939,.013695,
.016759,.014368,
.016464,.015,
.016064,.015571,
.015571,.016064,
.015,.016464,
.014368,.016759,
.013695,.016939,
.013,.017,
0.0*
%
%ADD35MACRO35*%
%AMMACRO24*
4,1,40,.017,-.013,
.017,.013,
.016939,.013695,
.016759,.014368,
.016464,.015,
.016064,.015571,
.015571,.016064,
.015,.016464,
.014368,.016759,
.013695,.016939,
.013,.017,
-.013,.017,
-.013695,.016939,
-.014368,.016759,
-.015,.016464,
-.015571,.016064,
-.016064,.015571,
-.016464,.015,
-.016759,.014368,
-.016939,.013695,
-.017,.013,
-.017,-.013,
-.016939,-.013695,
-.016759,-.014368,
-.016464,-.015,
-.016064,-.015571,
-.015571,-.016064,
-.015,-.016464,
-.014368,-.016759,
-.013695,-.016939,
-.013,-.017,
.013,-.017,
.013695,-.016939,
.014368,-.016759,
.015,-.016464,
.015571,-.016064,
.016064,-.015571,
.016464,-.015,
.016759,-.014368,
.016939,-.013695,
.017,-.013,
0.0*
%
%ADD24MACRO24*%
%AMMACRO64*
4,1,25,.26969,-.01299,
.26969,-.83465,
-.26969,-.83465,
-.26969,.83465,
.26969,.83465,
.26969,.12087,
.22638,.12087,
.214758,.119853,
.203489,.116834,
.192915,.111903,
.183358,.105211,
.175109,.096962,
.168417,.087405,
.163486,.076831,
.160467,.065562,
.15945,.05394,
.160467,.042318,
.163486,.031049,
.168417,.020475,
.175109,.010918,
.183358,.002669,
.192915,-.004023,
.203489,-.008954,
.214758,-.011973,
.22638,-.01299,
.26969,-.01299,
0.0*
%
%ADD64MACRO64*%
%AMMACRO52*
4,1,40,-.008,-.012,
.008,-.012,
.008695,-.011939,
.009368,-.011759,
.01,-.011464,
.010571,-.011064,
.011064,-.010571,
.011464,-.01,
.011759,-.009368,
.011939,-.008695,
.012,-.008,
.012,.008,
.011939,.008695,
.011759,.009368,
.011464,.01,
.011064,.010571,
.010571,.011064,
.01,.011464,
.009368,.011759,
.008695,.011939,
.008,.012,
-.008,.012,
-.008695,.011939,
-.009368,.011759,
-.01,.011464,
-.010571,.011064,
-.011064,.010571,
-.011464,.01,
-.011759,.009368,
-.011939,.008695,
-.012,.008,
-.012,-.008,
-.011939,-.008695,
-.011759,-.009368,
-.011464,-.01,
-.011064,-.010571,
-.010571,-.011064,
-.01,-.011464,
-.009368,-.011759,
-.008695,-.011939,
-.008,-.012,
0.0*
%
%ADD52MACRO52*%
%AMMACRO32*
4,1,40,.012,-.008,
.012,.008,
.011939,.008695,
.011759,.009368,
.011464,.01,
.011064,.010571,
.010571,.011064,
.01,.011464,
.009368,.011759,
.008695,.011939,
.008,.012,
-.008,.012,
-.008695,.011939,
-.009368,.011759,
-.01,.011464,
-.010571,.011064,
-.011064,.010571,
-.011464,.01,
-.011759,.009368,
-.011939,.008695,
-.012,.008,
-.012,-.008,
-.011939,-.008695,
-.011759,-.009368,
-.011464,-.01,
-.011064,-.010571,
-.010571,-.011064,
-.01,-.011464,
-.009368,-.011759,
-.008695,-.011939,
-.008,-.012,
.008,-.012,
.008695,-.011939,
.009368,-.011759,
.01,-.011464,
.010571,-.011064,
.011064,-.010571,
.011464,-.01,
.011759,-.009368,
.011939,-.008695,
.012,-.008,
0.0*
%
%ADD32MACRO32*%
%AMMACRO21*
4,1,40,-.007,-.011,
.007,-.011,
.007695,-.010939,
.008368,-.010759,
.009,-.010464,
.009571,-.010064,
.010064,-.009571,
.010464,-.009,
.010759,-.008368,
.010939,-.007695,
.011,-.007,
.011,.007,
.010939,.007695,
.010759,.008368,
.010464,.009,
.010064,.009571,
.009571,.010064,
.009,.010464,
.008368,.010759,
.007695,.010939,
.007,.011,
-.007,.011,
-.007695,.010939,
-.008368,.010759,
-.009,.010464,
-.009571,.010064,
-.010064,.009571,
-.010464,.009,
-.010759,.008368,
-.010939,.007695,
-.011,.007,
-.011,-.007,
-.010939,-.007695,
-.010759,-.008368,
-.010464,-.009,
-.010064,-.009571,
-.009571,-.010064,
-.009,-.010464,
-.008368,-.010759,
-.007695,-.010939,
-.007,-.011,
0.0*
%
%ADD21MACRO21*%
%AMMACRO20*
4,1,40,-.011,.007,
-.011,-.007,
-.010939,-.007695,
-.010759,-.008368,
-.010464,-.009,
-.010064,-.009571,
-.009571,-.010064,
-.009,-.010464,
-.008368,-.010759,
-.007695,-.010939,
-.007,-.011,
.007,-.011,
.007695,-.010939,
.008368,-.010759,
.009,-.010464,
.009571,-.010064,
.010064,-.009571,
.010464,-.009,
.010759,-.008368,
.010939,-.007695,
.011,-.007,
.011,.007,
.010939,.007695,
.010759,.008368,
.010464,.009,
.010064,.009571,
.009571,.010064,
.009,.010464,
.008368,.010759,
.007695,.010939,
.007,.011,
-.007,.011,
-.007695,.010939,
-.008368,.010759,
-.009,.010464,
-.009571,.010064,
-.010064,.009571,
-.010464,.009,
-.010759,.008368,
-.010939,.007695,
-.011,.007,
0.0*
%
%ADD20MACRO20*%
%ADD86C,.02*%
%ADD87C,.006*%
G75*
%LPD*%
G75*
G36*
G01X77800Y444315D02*
X86350D01*
Y453265D01*
X77800D01*
Y444315D01*
G37*
G36*
G01X66650D02*
X75200D01*
Y453265D01*
X66650D01*
Y444315D01*
G37*
G36*
G01X77800Y455865D02*
X86350D01*
Y464815D01*
X77800D01*
Y455865D01*
G37*
G36*
G01X66650D02*
X75200D01*
Y464815D01*
X66650D01*
Y455865D01*
G37*
G36*
G01X69200Y1579915D02*
X77750D01*
Y1588865D01*
X69200D01*
Y1579915D01*
G37*
G36*
G01X58050D02*
X66600D01*
Y1588865D01*
X58050D01*
Y1579915D01*
G37*
G36*
G01X69200Y1591465D02*
X77750D01*
Y1600415D01*
X69200D01*
Y1591465D01*
G37*
G36*
G01X58050D02*
X66600D01*
Y1600415D01*
X58050D01*
Y1591465D01*
G37*
G36*
G01X105300Y443815D02*
X113850D01*
Y452765D01*
X105300D01*
Y443815D01*
G37*
G36*
G01X94150D02*
X102700D01*
Y452765D01*
X94150D01*
Y443815D01*
G37*
G36*
G01X105300Y455365D02*
X113850D01*
Y464315D01*
X105300D01*
Y455365D01*
G37*
G36*
G01X94150D02*
X102700D01*
Y464315D01*
X94150D01*
Y455365D01*
G37*
G36*
G01X108556Y686015D02*
Y692015D01*
X104356D01*
Y686015D01*
X108556D01*
G37*
G36*
G01Y677815D02*
Y683815D01*
X104356D01*
Y677815D01*
X108556D01*
G37*
G36*
G01X102156Y686015D02*
Y692015D01*
X97956D01*
Y686015D01*
X102156D01*
G37*
G36*
G01Y677815D02*
Y683815D01*
X97956D01*
Y677815D01*
X102156D01*
G37*
G36*
G01X126150Y1579815D02*
X134700D01*
Y1588765D01*
X126150D01*
Y1579815D01*
G37*
G36*
G01Y1591365D02*
X134700D01*
Y1600315D01*
X126150D01*
Y1591365D01*
G37*
G36*
G01X102300Y1579815D02*
X110850D01*
Y1588765D01*
X102300D01*
Y1579815D01*
G37*
G36*
G01X91150D02*
X99700D01*
Y1588765D01*
X91150D01*
Y1579815D01*
G37*
G36*
G01X102300Y1591365D02*
X110850D01*
Y1600315D01*
X102300D01*
Y1591365D01*
G37*
G36*
G01X91150D02*
X99700D01*
Y1600315D01*
X91150D01*
Y1591365D01*
G37*
G36*
G01X149800Y443815D02*
X158350D01*
Y452765D01*
X149800D01*
Y443815D01*
G37*
G36*
G01X138650D02*
X147200D01*
Y452765D01*
X138650D01*
Y443815D01*
G37*
G36*
G01X177800D02*
X186350D01*
Y452765D01*
X177800D01*
Y443815D01*
G37*
G36*
G01X166650D02*
X175200D01*
Y452765D01*
X166650D01*
Y443815D01*
G37*
G36*
G01X149800Y455365D02*
X158350D01*
Y464315D01*
X149800D01*
Y455365D01*
G37*
G36*
G01X138650D02*
X147200D01*
Y464315D01*
X138650D01*
Y455365D01*
G37*
G36*
G01X177800D02*
X186350D01*
Y464315D01*
X177800D01*
Y455365D01*
G37*
G36*
G01X166650D02*
X175200D01*
Y464315D01*
X166650D01*
Y455365D01*
G37*
G36*
G01X171300Y1579815D02*
X179850D01*
Y1588765D01*
X171300D01*
Y1579815D01*
G37*
G36*
G01X160150D02*
X168700D01*
Y1588765D01*
X160150D01*
Y1579815D01*
G37*
G36*
G01X171300Y1591365D02*
X179850D01*
Y1600315D01*
X171300D01*
Y1591365D01*
G37*
G36*
G01X160150D02*
X168700D01*
Y1600315D01*
X160150D01*
Y1591365D01*
G37*
G36*
G01X137300Y1579815D02*
X145850D01*
Y1588765D01*
X137300D01*
Y1579815D01*
G37*
G36*
G01Y1591365D02*
X145850D01*
Y1600315D01*
X137300D01*
Y1591365D01*
G37*
G54D10*
X-222440Y19685D03*
Y1948818D03*
X643700Y19685D03*
Y1948818D03*
G54D20*
X19283Y310682D03*
X25900Y1725100D03*
X57400Y211300D03*
X56900Y240000D03*
X56600Y195000D03*
X32700Y256900D03*
X63000Y267700D03*
X39200Y347200D03*
X81400Y533900D03*
X78400Y591000D03*
X49600Y576900D03*
X61400Y676800D03*
X57400D03*
X64100Y912800D03*
X77002Y1137897D03*
X32900Y1664200D03*
X96100Y533900D03*
X124900Y588604D03*
X120800D03*
X93065Y597471D03*
X97265D03*
X92465Y610371D03*
X95200Y665700D03*
X110900Y884800D03*
X102600D03*
X119300D03*
X122529Y955744D03*
X117529D03*
X112529D03*
X100500Y1423700D03*
X91500D03*
X83500Y1465200D03*
X105000Y1423700D03*
X107500Y1490200D03*
X170600Y532500D03*
X155600Y532400D03*
X158000Y578600D03*
X170200Y627100D03*
X180365Y645771D03*
X137765Y662071D03*
X154500Y687200D03*
X149500Y711700D03*
X147900Y1003100D03*
X152100Y1003200D03*
X163500Y997700D03*
X159500D03*
X143800Y1003200D03*
X135000Y1411804D03*
X134700Y1404004D03*
X137500Y1443700D03*
G54D11*
X-181139Y20007D03*
X-180444Y1947256D03*
X601704Y21248D03*
X602399Y1948497D03*
G54D21*
X29100Y321300D03*
X30100Y1083600D03*
X18600Y1644300D03*
X18400Y1720700D03*
X20200Y1692800D03*
X56900Y155300D03*
Y163300D03*
Y179300D03*
Y159300D03*
Y175300D03*
X46500Y213400D03*
X57800Y217000D03*
X56900Y199300D03*
X32800Y272300D03*
X70800Y431300D03*
X61000Y577200D03*
X78556Y690465D03*
X80700Y686400D03*
X45400Y916400D03*
X68700Y999800D03*
X49400Y1769800D03*
X88303Y61502D03*
X85800Y71500D03*
X117900Y437500D03*
X125956Y692165D03*
X125856Y688065D03*
Y683665D03*
X112900Y670600D03*
X83996Y848500D03*
Y844100D03*
Y852900D03*
X84000Y865700D03*
Y857200D03*
Y861500D03*
X111900Y1408200D03*
X91300Y1451000D03*
X109700Y1425900D03*
X91300Y1439000D03*
X84300Y1484000D03*
X128800Y1482000D03*
X159900Y545600D03*
X162700Y622700D03*
X152329Y615065D03*
X171800Y701100D03*
X152096Y1415000D03*
X140500Y1458400D03*
X152100Y1423400D03*
X152096Y1419200D03*
X190800Y439500D03*
G54D12*
X29921Y24803D03*
Y111417D03*
Y458031D03*
Y544646D03*
Y717874D03*
Y804488D03*
X30000Y1164000D03*
X29921Y1250630D03*
Y1423858D03*
Y1510472D03*
Y1857086D03*
Y1943701D03*
G54D30*
X28000Y1769900D03*
X75700Y71500D03*
X58200Y662300D03*
Y657600D03*
X48700Y1764700D03*
X110200Y769100D03*
Y764100D03*
X99700Y1058400D03*
Y1053700D03*
X182300Y1652700D03*
Y1648000D03*
X141847Y1878698D03*
X141800Y1883700D03*
G54D22*
X22900Y397800D03*
Y418300D03*
X19100Y667000D03*
X81100Y398500D03*
X47700Y397800D03*
X81100Y419000D03*
X47700Y418300D03*
X43900Y667000D03*
X73600Y798400D03*
X63700Y1090600D03*
X36600Y1551500D03*
X61400D03*
X113100Y88500D03*
X105900Y398500D03*
Y419000D03*
X98400Y798400D03*
X88500Y1090600D03*
X137900Y88500D03*
X185300Y397900D03*
X160500D03*
X185200Y356700D03*
X160400D03*
X185400Y376900D03*
X160600D03*
X185300Y418400D03*
X160500D03*
X184900Y1531500D03*
X160100D03*
X185000Y1551600D03*
X160200D03*
G54D31*
X21350Y1781000D03*
X77953Y54502D03*
X71650Y584000D03*
X58350D03*
X45050Y593000D03*
X58350D03*
X81850Y715400D03*
X81350Y740400D03*
X60150Y1011800D03*
X73450D03*
X64450Y1032100D03*
X77750D03*
X34650Y1781000D03*
X91253Y54502D03*
X95850Y68500D03*
X109150D03*
X95150Y715400D03*
X94650Y740400D03*
G54D40*
X71802Y52947D03*
X71400Y68154D03*
X75200Y737900D03*
X75700Y715500D03*
X53800Y1009500D03*
X103500Y593900D03*
X146365Y607721D03*
G54D13*
X15906Y48110D03*
Y58110D03*
Y68110D03*
Y78110D03*
Y88110D03*
Y481339D03*
Y491339D03*
Y501339D03*
Y511339D03*
Y521339D03*
Y741181D03*
Y751181D03*
Y761181D03*
Y771181D03*
Y781181D03*
Y1187323D03*
Y1197323D03*
Y1207323D03*
Y1217323D03*
Y1227323D03*
Y1447165D03*
Y1457165D03*
Y1467165D03*
Y1477165D03*
Y1487165D03*
Y1880394D03*
Y1890394D03*
Y1900394D03*
Y1910394D03*
Y1920394D03*
X128937Y1778819D03*
X118937D03*
X165000Y1390500D03*
Y1380500D03*
Y1370500D03*
X138937Y1778819D03*
G54D32*
X30300Y1787800D03*
X64500Y573000D03*
X71200Y1144500D03*
X81900Y966200D03*
X87000Y1143000D03*
X94800Y1431500D03*
Y1434900D03*
Y1442800D03*
X163400Y549300D03*
X144300Y695500D03*
X133300Y1432000D03*
G54D14*
X27559Y157480D03*
Y629921D03*
X17716Y1338583D03*
X27559Y1811023D03*
X179134Y78740D03*
X179133Y570866D03*
X179134Y1161417D03*
Y1889764D03*
G54D41*
X47244Y68110D03*
Y501338D03*
Y761181D03*
Y1207323D03*
Y1467165D03*
Y1900393D03*
G54D50*
X72000Y473548D03*
Y491452D03*
X90000Y473548D03*
Y491452D03*
X176000Y473048D03*
Y490952D03*
X158000Y473048D03*
Y490952D03*
G54D23*
X30000Y570800D03*
X24300Y1106000D03*
X18600Y1640200D03*
X19900Y1769600D03*
X67300Y63500D03*
X56900Y171300D03*
Y183300D03*
Y167300D03*
Y187300D03*
X57800Y221000D03*
X46500Y217400D03*
X32682Y264217D03*
X56900Y280000D03*
X78544Y694635D03*
X80000Y682200D03*
X65300Y730000D03*
X68700Y1004300D03*
X59600Y1020600D03*
X72300Y1025400D03*
X72400Y1020900D03*
X38000Y1096000D03*
X68800Y1175100D03*
X30700Y1774400D03*
X35000Y1788200D03*
X98700Y549600D03*
X83700Y569900D03*
X91300Y671000D03*
X115600Y660200D03*
X104900Y662200D03*
X87800Y707900D03*
X86300Y733400D03*
X104100Y1408100D03*
X129800Y1428300D03*
X91300Y1446500D03*
X109700Y1421600D03*
X150100Y430800D03*
X145300Y568000D03*
X152800Y587000D03*
X162700Y626700D03*
X174300Y624300D03*
X148004Y1394000D03*
X140500Y1466400D03*
Y1462400D03*
X140200Y1453300D03*
X157300Y1458000D03*
G54D24*
X24100Y690900D03*
X28900D03*
X74100Y576200D03*
X65635Y693906D03*
X70535D03*
X82000Y708200D03*
X72200Y711000D03*
X67200D03*
X70800Y981400D03*
X64200Y1004100D03*
X81398Y1137753D03*
X92300Y878454D03*
X87500D03*
X94000Y962800D03*
X103500Y979800D03*
X129900Y992500D03*
X140400Y572400D03*
X158535Y609679D03*
G54D33*
X26700Y1787800D03*
X60900Y573000D03*
X78300Y966200D03*
X67600Y1144500D03*
X83400Y1143000D03*
X91200Y1431500D03*
Y1434900D03*
X129700Y1432000D03*
X91200Y1442800D03*
X159800Y549300D03*
X140700Y695500D03*
G54D60*
X70202Y1138347D03*
Y1125047D03*
X41600Y1767550D03*
Y1754250D03*
X88502Y1136247D03*
Y1122947D03*
G54D42*
X80709Y119409D03*
Y329409D03*
X149606Y119409D03*
Y329409D03*
G54D15*
X31299Y230866D03*
Y220866D03*
Y210866D03*
Y338563D03*
Y358563D03*
Y348563D03*
Y903917D03*
Y923917D03*
Y913917D03*
Y1054587D03*
Y1044587D03*
Y1064587D03*
Y1619941D03*
Y1609941D03*
Y1629941D03*
Y1757638D03*
Y1747638D03*
Y1737638D03*
G54D51*
X73900Y550100D03*
X132735Y593429D03*
X125835Y593629D03*
X92971Y617335D03*
X131935Y601929D03*
X105000Y603200D03*
X101900Y654100D03*
X117100Y1430100D03*
X136771Y548521D03*
X144329Y598765D03*
X140135Y593229D03*
X160700Y615900D03*
X151029Y627565D03*
X139929Y604165D03*
X156700Y626800D03*
X179000Y706500D03*
X147600Y994600D03*
X154000Y994500D03*
X142000D03*
G54D52*
X35000Y581300D03*
X58100Y1030800D03*
X87400Y574100D03*
X149500Y578600D03*
X164600Y608500D03*
X150500Y699200D03*
G54D70*
X89435Y642629D03*
Y635029D03*
X89500Y1461700D03*
Y1469300D03*
X172100Y549100D03*
Y541500D03*
X170100Y607600D03*
Y615200D03*
X152265Y608971D03*
Y601371D03*
X167000Y1457700D03*
Y1465300D03*
G54D61*
X80200Y1477500D03*
X107600Y558300D03*
X115200D03*
X87800Y1477500D03*
X106770Y1480640D03*
X99170D03*
X183700Y1606500D03*
X180700Y1641000D03*
X191300Y1606500D03*
X188300Y1641000D03*
G54D16*
X27471Y262553D03*
X19721D03*
X23596Y255053D03*
X24925Y305350D03*
X28800Y312850D03*
X27625Y1649050D03*
X27292Y1714868D03*
X19542D03*
X23417Y1707368D03*
X32675Y305350D03*
X54817Y902368D03*
X58692Y909868D03*
X50942D03*
X78752Y1613297D03*
Y1619703D03*
X35375Y1649050D03*
X31500Y1641550D03*
X131525Y722550D03*
X109252Y1613297D03*
Y1619703D03*
X141625Y682250D03*
X149375D03*
X145500Y689750D03*
X139275Y722550D03*
X135400Y730050D03*
X148025Y1401454D03*
X155775D03*
X151900Y1408954D03*
X165494Y1437469D03*
X173244D03*
X169369Y1444969D03*
X138694Y1422269D03*
X146444D03*
X142569Y1429769D03*
X137752Y1613297D03*
Y1619703D03*
X165252Y1613297D03*
Y1619703D03*
G54D43*
X80709Y139409D03*
Y309409D03*
X149606Y139409D03*
Y309409D03*
G54D34*
X72200Y86200D03*
X72602Y757897D03*
X63700Y1050100D03*
X99000Y86200D03*
X99402Y757897D03*
X90500Y1050100D03*
G54D25*
X24100Y685300D03*
X28900D03*
X74100Y570600D03*
X82000Y702600D03*
X65635Y688306D03*
X70535D03*
X72200Y705400D03*
X67200D03*
X70800Y975800D03*
X64200Y998500D03*
X81398Y1132153D03*
X92300Y872854D03*
X87500D03*
X94000Y957200D03*
X103500Y974200D03*
X129900Y986900D03*
X140400Y566800D03*
X158535Y604079D03*
G54D35*
X78247Y61398D03*
X50600Y252800D03*
X34400Y294300D03*
X67900Y591000D03*
X71000Y986600D03*
X62000Y1025000D03*
X111300Y380100D03*
X85929Y533679D03*
X101500Y986000D03*
Y990800D03*
X89200Y1455500D03*
X101200Y1474500D03*
X160300Y532100D03*
X160100Y553300D03*
X176421Y613535D03*
X154700Y1462500D03*
G54D53*
X35000Y584900D03*
X58100Y1034400D03*
X87400Y577700D03*
X149500Y582200D03*
X164600Y612100D03*
X150500Y702800D03*
G54D62*
X78900Y1498700D03*
Y1523500D03*
X124298Y1908303D03*
Y1883503D03*
X145798Y1151303D03*
Y1126503D03*
G54D71*
X93206Y677415D03*
Y682415D03*
Y687415D03*
Y692415D03*
X113306D03*
Y687415D03*
Y682415D03*
Y677415D03*
G54D80*
X171370Y634819D03*
X159800D03*
X171370Y645839D03*
X159800D03*
G54D17*
X27900Y246900D03*
X25300Y328500D03*
X16200Y1657100D03*
X27200D03*
X15800Y1699200D03*
X26800D03*
X38900Y246900D03*
X36300Y328500D03*
X124696Y1392300D03*
X106000Y1387500D03*
X117000D03*
X135696Y1392300D03*
X154000Y1387500D03*
X143000D03*
G54D26*
X27700Y1106000D03*
X22000Y1640200D03*
X23300Y1769600D03*
X70700Y63500D03*
X60300Y171300D03*
Y183300D03*
Y167300D03*
Y187300D03*
X61200Y221000D03*
X49900Y217400D03*
X36082Y264217D03*
X60300Y280000D03*
X33400Y570800D03*
X68700Y730000D03*
X72100Y1004300D03*
X63000Y1020600D03*
X75700Y1025400D03*
X75800Y1020900D03*
X41400Y1096000D03*
X72200Y1175100D03*
X34100Y1774400D03*
X38400Y1788200D03*
X102100Y549600D03*
X87100Y569900D03*
X81944Y694635D03*
X94700Y671000D03*
X119000Y660200D03*
X108300Y662200D03*
X83400Y682200D03*
X91200Y707900D03*
X89700Y733400D03*
X107500Y1408100D03*
X94700Y1446500D03*
X113100Y1421600D03*
X153500Y430800D03*
X148700Y568000D03*
X156200Y587000D03*
X166100Y626700D03*
X177700Y624300D03*
X151404Y1394000D03*
X133200Y1428300D03*
X143900Y1466400D03*
Y1462400D03*
X143600Y1453300D03*
X160700Y1458000D03*
G54D44*
X80709Y161889D03*
Y171889D03*
Y181889D03*
Y191889D03*
Y204409D03*
Y214409D03*
Y224409D03*
Y234409D03*
Y244409D03*
Y256929D03*
Y266929D03*
Y276929D03*
Y286929D03*
X110709Y161889D03*
Y171889D03*
X100709Y161889D03*
Y171889D03*
X90709Y161889D03*
Y171889D03*
X110709Y181889D03*
Y191889D03*
X100709Y181889D03*
Y191889D03*
X90709Y181889D03*
Y191889D03*
X110709Y204409D03*
Y214409D03*
Y224409D03*
Y234409D03*
Y244409D03*
X100709Y204409D03*
Y214409D03*
Y224409D03*
Y234409D03*
Y244409D03*
X90709Y204409D03*
Y214409D03*
Y224409D03*
Y234409D03*
Y244409D03*
X110709Y256929D03*
Y266929D03*
X100709Y256929D03*
Y266929D03*
X90709Y256929D03*
Y266929D03*
X110709Y276929D03*
Y286929D03*
X100709Y276929D03*
Y286929D03*
X90709Y276929D03*
Y286929D03*
X179606Y161889D03*
Y171889D03*
X169606Y161889D03*
Y171889D03*
X159606Y161889D03*
Y171889D03*
X149606Y161889D03*
Y171889D03*
X179606Y181889D03*
Y191889D03*
X169606Y181889D03*
Y191889D03*
X159606Y181889D03*
Y191889D03*
X149606Y181889D03*
Y191889D03*
X179606Y204409D03*
Y214409D03*
Y224409D03*
Y234409D03*
Y244409D03*
X169606Y204409D03*
Y214409D03*
Y224409D03*
Y234409D03*
Y244409D03*
X159606Y204409D03*
Y214409D03*
Y224409D03*
Y234409D03*
Y244409D03*
X149606Y204409D03*
Y214409D03*
Y224409D03*
Y234409D03*
Y244409D03*
X179606Y256929D03*
Y266929D03*
X169606Y256929D03*
Y266929D03*
X159606Y256929D03*
Y266929D03*
X149606Y256929D03*
Y266929D03*
X179606Y276929D03*
Y286929D03*
X169606Y276929D03*
Y286929D03*
X159606Y276929D03*
Y286929D03*
X149606Y276929D03*
Y286929D03*
G54D63*
X71250Y1613297D03*
Y1619703D03*
X101750Y1613297D03*
Y1619703D03*
X130250Y1613297D03*
Y1619703D03*
X157750Y1613297D03*
Y1619703D03*
G54D72*
X134709Y710500D03*
X117291D03*
G54D27*
X24368Y1093083D03*
X31868Y1089208D03*
Y1096958D03*
X112018Y566991D03*
Y574741D03*
X104518Y570866D03*
X112018Y1255968D03*
Y1263718D03*
X104518Y1259843D03*
G54D45*
X47498Y238899D03*
X52200Y238900D03*
X62700Y254200D03*
X45100Y577300D03*
X81500Y727600D03*
X63202Y1128347D03*
X103900Y476600D03*
X96300Y557700D03*
X129065Y673094D03*
X123465D03*
X124900Y722600D03*
X94500Y976700D03*
X130800Y975800D03*
X146700Y476700D03*
X163300Y696500D03*
X144300Y1111300D03*
X149002Y1111347D03*
X133500Y1471200D03*
G54D36*
X81300Y71500D03*
X63800Y662300D03*
Y657600D03*
X54300Y1764700D03*
X33600Y1769900D03*
X115800Y769100D03*
Y764100D03*
X105300Y1058400D03*
Y1053700D03*
X147447Y1878698D03*
X147400Y1883700D03*
X187900Y1652700D03*
Y1648000D03*
G54D81*
X180465Y631371D03*
Y634971D03*
G54D54*
X73403Y633502D03*
Y606702D03*
X122097Y1125298D03*
Y1152098D03*
X98497Y1883198D03*
Y1909998D03*
G54D18*
X18600Y249100D03*
X27900Y269471D03*
X20010Y302982D03*
X11000Y578000D03*
X27300Y593000D03*
X27100Y578100D03*
X24500Y1102000D03*
X20056Y1774189D03*
X43900Y137200D03*
X36200Y318700D03*
X63200Y385100D03*
X62400Y430600D03*
X62900Y412900D03*
X61700Y421900D03*
X70900Y427200D03*
X66000Y510500D03*
X77400Y536300D03*
X70400Y565500D03*
X49665Y642933D03*
X43337Y650145D03*
X37000Y605000D03*
X57200Y667884D03*
X65000Y775000D03*
Y766000D03*
X43100Y866100D03*
X76500Y900500D03*
X65900Y900000D03*
X64100Y904800D03*
X73000Y966000D03*
X66900Y969100D03*
X60000Y966800D03*
X81500Y985900D03*
X51500Y974100D03*
X37200Y1091700D03*
X52100Y1132700D03*
X71000Y1232600D03*
X33000Y1575000D03*
X53300Y1609200D03*
X64400Y1605900D03*
X62300Y1641300D03*
X59500Y1627500D03*
X32900Y1656300D03*
X61500Y1716500D03*
X72500Y1717000D03*
Y1699000D03*
X33000Y1718500D03*
X32949Y1709451D03*
X79000Y1766500D03*
X71500Y1760000D03*
X72500Y1733000D03*
X81000Y1802000D03*
X73000Y1813000D03*
X72000Y1798000D03*
X57000Y1805500D03*
X75500Y1838500D03*
X73000Y1847000D03*
X72500Y1830000D03*
X66000Y1917000D03*
X118500Y442000D03*
X122500Y429000D03*
X125100Y408900D03*
X115000Y486100D03*
X106500Y469500D03*
X115500Y476700D03*
X96900Y541600D03*
X99800Y545600D03*
X120800Y598700D03*
X112018Y584900D03*
X106338Y580496D03*
X118565Y592846D03*
X83619Y581742D03*
X82900Y574500D03*
X101800Y557400D03*
X96500Y567600D03*
X99578Y605771D03*
X93063Y629134D03*
X94545Y601197D03*
X91463Y623143D03*
X122088Y665912D03*
X119300Y656600D03*
X111400Y658500D03*
X86060Y695200D03*
X86000Y689900D03*
X125202Y657500D03*
X129000Y653600D03*
X95500Y728000D03*
X105500Y732000D03*
X117500Y724500D03*
X109000Y809500D03*
X119300Y837000D03*
X92400Y848900D03*
X103400Y838300D03*
X98700Y877100D03*
X92800Y865300D03*
X111100Y876700D03*
X92700Y858100D03*
X108200Y953500D03*
X112984Y946835D03*
X120054Y945600D03*
X130903Y958178D03*
X94500Y950500D03*
X110400Y997850D03*
X119080Y992900D03*
X127700Y998400D03*
X87600Y965900D03*
X90542Y987958D03*
X97958Y966958D03*
X103500Y966500D03*
X130900Y1003400D03*
X91500Y1030500D03*
X85500Y1009500D03*
X128500Y1076800D03*
X122862Y1385500D03*
X129000Y1416425D03*
X99500Y1407500D03*
X100000Y1443000D03*
X101000Y1460750D03*
X113024Y1452079D03*
X117122Y1448001D03*
X117195Y1456070D03*
X121338Y1452021D03*
X117024Y1452000D03*
X100200Y1433800D03*
X99700Y1450700D03*
X103000Y1429500D03*
X123000Y1431300D03*
X126975Y1435400D03*
X127300Y1468800D03*
X111833Y1469667D03*
X117500Y1519500D03*
X104333Y1498167D03*
X130180Y1486680D03*
X98000Y1564700D03*
X89500Y1610000D03*
X120500Y1606000D03*
X98500Y1717000D03*
Y1696500D03*
X99000Y1707000D03*
X109500Y1719500D03*
X110000Y1709500D03*
X109500Y1699000D03*
X119500Y1710110D03*
Y1696610D03*
X86500Y1713610D03*
Y1700110D03*
X119500Y1725110D03*
X111500Y1768500D03*
X108500Y1727000D03*
X117500Y1732000D03*
X119500Y1760000D03*
X97500Y1775500D03*
X86500Y1726000D03*
X87000Y1774110D03*
X119500Y1747110D03*
X110500Y1801000D03*
X88500Y1785000D03*
X97500Y1796000D03*
X98000Y1786000D03*
X86500Y1793110D03*
X108268Y1777300D03*
X107768Y1789110D03*
X120000Y1811500D03*
X119500Y1796500D03*
X84000Y1869600D03*
X114000Y1843500D03*
X97000Y1850500D03*
X120500Y1836500D03*
Y1850500D03*
X108500Y1851610D03*
X85100Y1844500D03*
X85700Y1852300D03*
X82000Y1915000D03*
X162612Y438169D03*
X143400Y408200D03*
X144400Y470800D03*
X149000Y522500D03*
X174800Y532200D03*
X151500Y533000D03*
X164200Y541900D03*
X149500Y574600D03*
X145230Y571700D03*
X135200Y566400D03*
X176300Y608635D03*
X157200Y620800D03*
X146663Y634051D03*
X148595Y618300D03*
X151335Y640400D03*
X145200Y644600D03*
X163100Y604717D03*
X179017Y620013D03*
X174100Y652900D03*
X153200Y653200D03*
X173000Y691000D03*
X142000Y701000D03*
X158500Y695000D03*
X145500Y675000D03*
X145000Y711750D03*
X167600Y703300D03*
X160500Y916500D03*
X133500Y953000D03*
X139500Y951500D03*
X143100Y1007100D03*
X162000Y1027000D03*
X178500Y1268500D03*
X159774Y1414374D03*
X136100Y1463900D03*
X134400Y1454300D03*
X133000Y1447600D03*
X165500Y1450600D03*
X138000Y1448500D03*
X142400Y1499900D03*
X136500Y1481425D03*
X148500Y1479500D03*
X136500Y1651000D03*
X139000Y1696500D03*
Y1712500D03*
X181500Y1716500D03*
X158500D03*
X167500Y1716000D03*
X182000Y1704000D03*
X168500Y1705000D03*
X158500D03*
X163000Y1697000D03*
X174268Y1697110D03*
X152000D03*
Y1710610D03*
Y1725610D03*
X138500Y1727500D03*
X182000Y1726000D03*
X183600Y1765100D03*
X162500Y1773000D03*
X152500Y1771110D03*
X173268Y1776000D03*
X139000Y1800500D03*
X138000Y1824000D03*
X169000Y1781500D03*
X156500Y1782000D03*
X155500Y1798500D03*
X166500Y1798000D03*
X179000Y1798500D03*
X162000Y1790000D03*
X172768Y1790110D03*
X152000D03*
X137000Y1877500D03*
X139000Y1851000D03*
X138500Y1839500D03*
X161500Y1852500D03*
X183100Y1838300D03*
X173000Y1852610D03*
X151500Y1851110D03*
X139861Y1889461D03*
X189928Y435800D03*
X197500Y481500D03*
X186000Y1133000D03*
X189000Y1432000D03*
X184500Y1696500D03*
X185000Y1738500D03*
X185500Y1804500D03*
X186000Y1790000D03*
X185000Y1852500D03*
G54D64*
X96457Y1773425D03*
G54D19*
X19283Y307282D03*
X25900Y1721700D03*
X57400Y207900D03*
X56900Y236600D03*
X56600Y191600D03*
X32700Y253500D03*
X63000Y264300D03*
X39200Y343800D03*
X81400Y530500D03*
X78400Y587600D03*
X49600Y573500D03*
X61400Y673400D03*
X57400D03*
X64100Y909400D03*
X77002Y1134497D03*
X32900Y1660800D03*
X96100Y530500D03*
X124900Y585204D03*
X120800D03*
X93065Y594071D03*
X97265D03*
X92465Y606971D03*
X95200Y662300D03*
X110900Y881400D03*
X102600D03*
X119300D03*
X122529Y952344D03*
X117529D03*
X112529D03*
X100500Y1420300D03*
X91500D03*
X83500Y1461800D03*
X105000Y1420300D03*
X107500Y1486800D03*
X170600Y529100D03*
X155600Y529000D03*
X158000Y575200D03*
X170200Y623700D03*
X180365Y642371D03*
X137765Y658671D03*
X154500Y683800D03*
X149500Y708300D03*
X147900Y999700D03*
X152100Y999800D03*
X163500Y994300D03*
X159500D03*
X143800Y999800D03*
X135000Y1408404D03*
X134700Y1400604D03*
X137500Y1440300D03*
G54D28*
X22000Y1644300D03*
X21800Y1720700D03*
X23600Y1692800D03*
X60300Y155300D03*
Y163300D03*
Y179300D03*
Y159300D03*
Y175300D03*
X49900Y213400D03*
X61200Y217000D03*
X60300Y199300D03*
X36200Y272300D03*
X32500Y321300D03*
X74200Y431300D03*
X64400Y577200D03*
X48800Y916400D03*
X72100Y999800D03*
X33500Y1083600D03*
X52800Y1769800D03*
X91703Y61502D03*
X89200Y71500D03*
X121300Y437500D03*
X81956Y690465D03*
X84100Y686400D03*
X129356Y692165D03*
X129256Y688065D03*
Y683665D03*
X116300Y670600D03*
X87396Y848500D03*
Y844100D03*
Y852900D03*
X87400Y865700D03*
Y857200D03*
Y861500D03*
X115300Y1408200D03*
X94700Y1451000D03*
X113100Y1425900D03*
X94700Y1439000D03*
X87700Y1484000D03*
X132200Y1482000D03*
X163300Y545600D03*
X166100Y622700D03*
X155729Y615065D03*
X175200Y701100D03*
X155496Y1415000D03*
X143900Y1458400D03*
X155500Y1423400D03*
X155496Y1419200D03*
X194200Y439500D03*
G54D55*
X66875Y674606D03*
X69435D03*
X71995D03*
Y681106D03*
X66875D03*
G54D82*
X141100Y1401696D03*
Y1410096D03*
X158600Y1446404D03*
Y1438004D03*
G54D73*
X116175Y846304D03*
X113620D03*
X111060D03*
X108500D03*
X105940D03*
X103380D03*
X100825D03*
Y868504D03*
X103380D03*
X105940D03*
X108500D03*
X111060D03*
X113620D03*
X116175D03*
X113960Y985200D03*
X116520D03*
X119080D03*
X121640D03*
Y963000D03*
X119080D03*
X116520D03*
X113960D03*
X155825Y732304D03*
X158380D03*
X160940D03*
X163500D03*
X166060D03*
X168620D03*
X171175D03*
Y710104D03*
X168620D03*
X166060D03*
X163500D03*
X160940D03*
X158380D03*
X155825D03*
X137340Y959500D03*
X139900D03*
X142460D03*
X145020D03*
X147580D03*
X150140D03*
X152700D03*
X155260D03*
Y981700D03*
X152700D03*
X150140D03*
X147580D03*
X145020D03*
X142460D03*
X139900D03*
X137340D03*
G54D46*
X47498Y244499D03*
X52200Y244500D03*
X62700Y259800D03*
X45100Y582900D03*
X81500Y733200D03*
X63202Y1133947D03*
X103900Y482200D03*
X96300Y563300D03*
X129065Y678694D03*
X123465D03*
X124900Y728200D03*
X94500Y982300D03*
X130800Y981400D03*
X146700Y482300D03*
X163300Y702100D03*
X144300Y1116900D03*
X149002Y1116947D03*
X133500Y1476800D03*
G54D37*
X67998Y56503D03*
X67398Y71003D03*
X61000Y240000D03*
X61600Y211300D03*
X60600Y195000D03*
X54300Y263300D03*
X58300D03*
X37200Y256900D03*
X62600Y249200D03*
X73700Y543300D03*
X78600Y574500D03*
X73900Y558800D03*
X39000Y581300D03*
X77200Y705900D03*
X77000Y730800D03*
X43400Y896100D03*
X81398Y1126103D03*
X63498Y1123803D03*
X63198Y1142003D03*
X48300Y1755700D03*
X116800Y588596D03*
X128900D03*
X91300Y573200D03*
X129335Y662029D03*
X104900Y662200D03*
X115600Y660200D03*
X116300Y670600D03*
X119600Y831800D03*
X111200D03*
X102900Y831796D03*
X121671Y939756D03*
X117300Y939700D03*
X110500D03*
X131500Y947800D03*
X123300Y1001300D03*
X119300D03*
X114800D03*
X99000Y979700D03*
X123000Y1424200D03*
X127500D03*
X95500Y1464200D03*
X118000Y1424200D03*
X95600Y1423700D03*
X129000Y1501700D03*
X125000D03*
X121000D03*
X117000D03*
X113000D03*
X109000D03*
X93500Y1479200D03*
X136779Y543071D03*
X145300Y582200D03*
X153500Y570000D03*
X136679Y557171D03*
X151335Y635829D03*
X148435Y653329D03*
X133535Y662029D03*
X144235Y653329D03*
X167700Y699600D03*
X154500Y702700D03*
X158500D03*
X149000Y949200D03*
X153000D03*
X157000D03*
X145000D03*
X140500Y947800D03*
X136000D03*
X139100Y1003100D03*
X135000Y1003200D03*
X156631Y1431081D03*
X160831Y1430281D03*
X152331Y1431081D03*
X165400Y1430200D03*
X151000Y1491200D03*
X146500D03*
X142000D03*
X137000Y1501700D03*
X133000D03*
X137900Y1491100D03*
X148500Y1474100D03*
G54D83*
X147500Y1437250D03*
X143625Y1444750D03*
X151375D03*
G54D56*
X51750Y690560D03*
Y688000D03*
Y685440D03*
X58250D03*
Y690560D03*
X36250D03*
Y688000D03*
Y685440D03*
X42750D03*
Y690560D03*
G54D74*
X113800Y1397140D03*
Y1399700D03*
Y1402260D03*
X106400D03*
Y1399700D03*
Y1397140D03*
G54D65*
X48200Y1760300D03*
X86800Y537800D03*
X96100D03*
X98600Y553300D03*
X107600Y593700D03*
X112900Y603500D03*
X170600Y536400D03*
X160900Y536500D03*
G54D38*
X67998Y53103D03*
X67398Y67603D03*
X61000Y236600D03*
X61600Y207900D03*
X60600Y191600D03*
X54300Y259900D03*
X58300D03*
X37200Y253500D03*
X62600Y245800D03*
X73700Y539900D03*
X78600Y571100D03*
X73900Y555400D03*
X39000Y577900D03*
X77200Y702500D03*
X77000Y727400D03*
X43400Y892700D03*
X81398Y1122703D03*
X63498Y1120403D03*
X63198Y1138603D03*
X48300Y1752300D03*
X116800Y585196D03*
X128900D03*
X91300Y569800D03*
X129335Y658629D03*
X104900Y658800D03*
X115600Y656800D03*
X116300Y667200D03*
X119600Y828400D03*
X111200D03*
X102900Y828396D03*
X121671Y936356D03*
X117300Y936300D03*
X110500D03*
X131500Y944400D03*
X123300Y997900D03*
X119300D03*
X114800D03*
X99000Y976300D03*
X123000Y1420800D03*
X127500D03*
X95500Y1460800D03*
X118000Y1420800D03*
X95600Y1420300D03*
X129000Y1498300D03*
X125000D03*
X121000D03*
X117000D03*
X113000D03*
X109000D03*
X93500Y1475800D03*
X136779Y539671D03*
X145300Y578800D03*
X153500Y566600D03*
X136679Y553771D03*
X151335Y632429D03*
X148435Y649929D03*
X144235D03*
X133535Y658629D03*
X154500Y699300D03*
X167700Y696200D03*
X158500Y699300D03*
X149000Y945800D03*
X153000D03*
X157000D03*
X145000D03*
X140500Y944400D03*
X136000D03*
X139100Y999700D03*
X135000Y999800D03*
X156631Y1427681D03*
X160831Y1426881D03*
X152331Y1427681D03*
X165400Y1426800D03*
X151000Y1487800D03*
X146500D03*
X142000D03*
X137000Y1498300D03*
X133000D03*
X137900Y1487700D03*
X148500Y1470700D03*
G54D29*
X32359Y1680500D03*
X60641D03*
G54D47*
X56200Y252800D03*
X40000Y294300D03*
X73500Y591000D03*
X76600Y986600D03*
X67600Y1025000D03*
X83847Y61398D03*
X116900Y380100D03*
X91529Y533679D03*
X107100Y986000D03*
Y990800D03*
X94800Y1455500D03*
X106800Y1474500D03*
X165900Y532100D03*
X165700Y553300D03*
X182021Y613535D03*
X160300Y1462500D03*
G54D57*
X49900Y883800D03*
Y894800D03*
X63800Y986600D03*
Y975600D03*
X39000Y1022500D03*
Y1033500D03*
X96000Y931000D03*
Y942000D03*
X147000Y732000D03*
Y721000D03*
G54D84*
X142300Y1471800D03*
Y1480800D03*
G54D39*
X71802Y56547D03*
X71400Y71754D03*
X75200Y741500D03*
X75700Y719100D03*
X53800Y1013100D03*
X103500Y597500D03*
X146365Y611321D03*
G54D66*
X51800Y1760300D03*
X90400Y537800D03*
X99700D03*
X102200Y553300D03*
X111200Y593700D03*
X116500Y603500D03*
X174200Y536400D03*
X164500Y536500D03*
G54D75*
X125000Y1409454D03*
X121125Y1401954D03*
X128875D03*
G54D48*
X69635Y361900D03*
X110735Y361800D03*
X99365Y361900D03*
X140465Y361800D03*
X157835Y1507700D03*
X187565D03*
G54D58*
X63901Y949600D03*
X86699D03*
G54D67*
X96457Y1747835D03*
Y1823031D03*
X178937Y1328740D03*
X161417Y1747835D03*
Y1823031D03*
G54D76*
X111882Y1461600D03*
X114441D03*
X117000D03*
X119559D03*
X122118D03*
Y1442400D03*
X119559D03*
X117000D03*
X114441D03*
X111882D03*
G54D49*
X69000Y440000D03*
X74000D03*
X79000D03*
X60400Y1575600D03*
X65400D03*
X70400D03*
X75400D03*
X96500Y439500D03*
X101500D03*
X106500D03*
X111500D03*
X84000Y440000D03*
X128500Y1575500D03*
X93500D03*
X98500D03*
X103500D03*
X108500D03*
X141000Y439500D03*
X146000D03*
X151000D03*
X156000D03*
X169000D03*
X174000D03*
X179000D03*
X184000D03*
X162500Y1575500D03*
X167500D03*
X172500D03*
X177500D03*
X133500D03*
X138500D03*
X143500D03*
G54D85*
X161417Y1773425D03*
G54D86*
G01X-448201Y-82763D02*
Y-162763D01*
G01Y-118263D02*
X752899D01*
G01X-448201Y-162763D02*
X752899D01*
G01X-452201Y-66763D02*
G02I-12000J0D01*
G01X-457351D02*
G02I-6850J0D01*
G01X-464201Y-82763D02*
Y-50763D01*
G01X-448201Y-66763D02*
X-480201D01*
G01X-448201Y-82763D02*
X752899D01*
G01X-34601D02*
Y-162763D01*
G01X102899Y-82763D02*
Y-162763D01*
G01X217899Y-82763D02*
Y-162763D01*
G01X385399Y-82763D02*
Y-162763D01*
G01X555399Y-82763D02*
Y-162763D01*
G01X752899Y-82763D02*
Y-162763D01*
G01X780899Y-66763D02*
G02I-12000J0D01*
G01X775749D02*
G02I-6850J0D01*
G01X768899Y-82763D02*
Y-50763D01*
G01X784899Y-66763D02*
X752899D01*
G54D77*
X126600Y1457118D03*
Y1454559D03*
Y1452000D03*
Y1449441D03*
Y1446882D03*
X107400D03*
Y1449441D03*
Y1452000D03*
Y1454559D03*
Y1457118D03*
G54D68*
X89335Y544750D03*
X87370D03*
X85400D03*
X83430D03*
X81465D03*
Y561050D03*
X83430D03*
X85400D03*
X87370D03*
X89335D03*
X108710Y612629D03*
X110675D03*
X112645D03*
X114615D03*
X116580D03*
X118550D03*
X120520D03*
X122490D03*
X124455D03*
X126425D03*
X128395D03*
X130360D03*
Y646029D03*
X128395D03*
X126425D03*
X124455D03*
X122490D03*
X120520D03*
X118550D03*
X116580D03*
X114615D03*
X112645D03*
X110675D03*
X108710D03*
X153135Y542950D03*
X151170D03*
X149200D03*
X147230D03*
X145265D03*
Y559250D03*
X147230D03*
X149200D03*
X151170D03*
X153135D03*
G54D59*
X77400Y980050D03*
Y976300D03*
Y972550D03*
X88000D03*
Y976300D03*
Y980050D03*
G54D87*
G01X-430254Y-152763D02*
Y-135263D01*
G01X-421958D02*
X-430254Y-146055D01*
G01X-420648Y-152763D02*
X-426543Y-141097D01*
G01X-412973Y-152763D02*
Y-135263D01*
X-402929Y-152763D01*
Y-135263D01*
G01X-390451Y-152763D02*
X-392198Y-152471D01*
X-393726Y-151305D01*
X-395036Y-149555D01*
X-395910Y-147513D01*
X-396346Y-145180D01*
Y-142846D01*
X-395910Y-140513D01*
X-395036Y-138471D01*
X-393726Y-136722D01*
X-392198Y-135555D01*
X-390451Y-135263D01*
X-388705Y-135555D01*
X-387176Y-136722D01*
X-385866Y-138471D01*
X-384992Y-140513D01*
X-384556Y-142846D01*
Y-145180D01*
X-384992Y-147513D01*
X-385866Y-149555D01*
X-387176Y-151305D01*
X-388705Y-152471D01*
X-390451Y-152763D01*
G01X-377536D02*
X-368366Y-135263D01*
G01X-377536D02*
X-368366Y-152763D01*
G01X-362001Y-158596D02*
X-348901D01*
G01X-342099Y-152763D02*
Y-135263D01*
X-333803D01*
G01X-336859Y-143721D02*
X-342099D01*
G01X-325910Y-152763D02*
X-320451Y-135263D01*
X-314992Y-152763D01*
G01X-316958Y-146638D02*
X-323945D01*
G01X-307973Y-152763D02*
Y-135263D01*
X-297929Y-152763D01*
Y-135263D01*
G01X-263148Y-136722D02*
X-264458Y-135846D01*
X-265986Y-135263D01*
X-267733D01*
X-269698Y-136138D01*
X-271226Y-137596D01*
X-272318Y-139347D01*
X-273191Y-142263D01*
X-273410Y-144888D01*
X-272973Y-147513D01*
X-272318Y-149263D01*
X-271008Y-151013D01*
X-269479Y-152180D01*
X-267951Y-152763D01*
X-266423D01*
X-264894Y-152180D01*
X-263584Y-151305D01*
X-262492Y-150139D01*
G01X-250451Y-152763D02*
X-252198Y-152471D01*
X-253726Y-151305D01*
X-255036Y-149555D01*
X-255910Y-147513D01*
X-256346Y-145180D01*
Y-142846D01*
X-255910Y-140513D01*
X-255036Y-138471D01*
X-253726Y-136722D01*
X-252198Y-135555D01*
X-250451Y-135263D01*
X-248705Y-135555D01*
X-247176Y-136722D01*
X-245866Y-138471D01*
X-244992Y-140513D01*
X-244556Y-142846D01*
Y-145180D01*
X-244992Y-147513D01*
X-245866Y-149555D01*
X-247176Y-151305D01*
X-248705Y-152471D01*
X-250451Y-152763D01*
G01X-237973D02*
Y-135263D01*
X-227929Y-152763D01*
Y-135263D01*
G01X-215451D02*
Y-152763D01*
G01X-220473Y-135263D02*
X-210429D01*
G01X-202318Y-152763D02*
Y-135263D01*
X-196859D01*
X-195113Y-136138D01*
X-194021Y-137305D01*
X-193584Y-139638D01*
X-194021Y-141972D01*
X-195331Y-143430D01*
X-196859Y-144305D01*
X-202318D01*
G01X-196859D02*
X-193584Y-152763D01*
G01X-180451D02*
X-182198Y-152471D01*
X-183726Y-151305D01*
X-185036Y-149555D01*
X-185910Y-147513D01*
X-186346Y-145180D01*
Y-142846D01*
X-185910Y-140513D01*
X-185036Y-138471D01*
X-183726Y-136722D01*
X-182198Y-135555D01*
X-180451Y-135263D01*
X-178705Y-135555D01*
X-177176Y-136722D01*
X-175866Y-138471D01*
X-174992Y-140513D01*
X-174556Y-142846D01*
Y-145180D01*
X-174992Y-147513D01*
X-175866Y-149555D01*
X-177176Y-151305D01*
X-178705Y-152471D01*
X-180451Y-152763D01*
G01X-167318Y-135263D02*
Y-152763D01*
X-158584D01*
G01X-126205Y-143430D02*
X-125331Y-142555D01*
X-124676Y-141097D01*
X-124239Y-139054D01*
X-124676Y-137305D01*
X-125549Y-136138D01*
X-127078Y-135263D01*
X-132973D01*
Y-152763D01*
X-125768D01*
X-124239Y-151597D01*
X-123366Y-149846D01*
X-122929Y-147805D01*
X-123366Y-145763D01*
X-124676Y-144013D01*
X-126205Y-143430D01*
X-132973D01*
G01X-110451Y-152763D02*
X-112198Y-152471D01*
X-113726Y-151305D01*
X-115036Y-149555D01*
X-115910Y-147513D01*
X-116346Y-145180D01*
Y-142846D01*
X-115910Y-140513D01*
X-115036Y-138471D01*
X-113726Y-136722D01*
X-112198Y-135555D01*
X-110451Y-135263D01*
X-108705Y-135555D01*
X-107176Y-136722D01*
X-105866Y-138471D01*
X-104992Y-140513D01*
X-104556Y-142846D01*
Y-145180D01*
X-104992Y-147513D01*
X-105866Y-149555D01*
X-107176Y-151305D01*
X-108705Y-152471D01*
X-110451Y-152763D01*
G01X-98410D02*
X-92951Y-135263D01*
X-87492Y-152763D01*
G01X-89458Y-146638D02*
X-96445D01*
G01X-79818Y-152763D02*
Y-135263D01*
X-74359D01*
X-72613Y-136138D01*
X-71521Y-137305D01*
X-71084Y-139638D01*
X-71521Y-141972D01*
X-72831Y-143430D01*
X-74359Y-144305D01*
X-79818D01*
G01X-74359D02*
X-71084Y-152763D01*
G01X-62754D02*
Y-135263D01*
X-58388D01*
X-56641Y-136138D01*
X-55331Y-137305D01*
X-54239Y-139054D01*
X-53366Y-141097D01*
X-53148Y-144013D01*
X-53366Y-146930D01*
X-54239Y-148972D01*
X-55331Y-150722D01*
X-56641Y-151888D01*
X-58388Y-152763D01*
X-62754D01*
G01X-282378Y-107763D02*
Y-90263D01*
X-276701Y-104846D01*
X-271024Y-90263D01*
Y-107763D01*
G01X-259201D02*
X-260511Y-107471D01*
X-261821Y-106305D01*
X-262695Y-104263D01*
X-263131Y-101930D01*
X-262695Y-99596D01*
X-261821Y-97555D01*
X-260511Y-96388D01*
X-259201Y-96097D01*
X-257891Y-96388D01*
X-256581Y-97555D01*
X-255708Y-99596D01*
X-255489Y-101930D01*
X-255708Y-104263D01*
X-256581Y-106305D01*
X-257891Y-107471D01*
X-259201Y-107763D01*
G01X-237771Y-90263D02*
Y-107763D01*
G01Y-105139D02*
X-238644Y-106597D01*
X-239955Y-107471D01*
X-241483Y-107763D01*
X-243229Y-107180D01*
X-244539Y-105722D01*
X-245413Y-103972D01*
X-245631Y-101930D01*
X-245413Y-99888D01*
X-244539Y-98138D01*
X-243229Y-96680D01*
X-241483Y-96097D01*
X-239955Y-96388D01*
X-238863Y-96972D01*
X-237771Y-98138D01*
G01X-227476Y-99888D02*
X-220489D01*
X-221144Y-97846D01*
X-222236Y-96680D01*
X-223764Y-96097D01*
X-225293Y-96388D01*
X-226603Y-97263D01*
X-227476Y-99305D01*
X-227913Y-101055D01*
Y-102805D01*
X-227476Y-104555D01*
X-226384Y-106305D01*
X-225074Y-107471D01*
X-223546Y-107763D01*
X-222018Y-107180D01*
X-220489Y-105430D01*
G01X-206701Y-107763D02*
Y-90263D01*
G01X-901Y-152763D02*
Y-135263D01*
X-3521Y-138763D01*
G01Y-152763D02*
X1719D01*
G01X12451Y-138180D02*
X13761Y-136430D01*
X15289Y-135555D01*
X17036Y-135263D01*
X19219Y-135846D01*
X20747Y-137305D01*
X21184Y-139054D01*
X20966Y-140805D01*
X20092Y-142263D01*
X15726Y-145180D01*
X13761Y-147221D01*
X12451Y-150139D01*
X12014Y-152763D01*
X21184D01*
G01X36719D02*
Y-135263D01*
X28640Y-147805D01*
X39558D01*
G01X46796Y-149263D02*
X48105Y-151305D01*
X49852Y-152471D01*
X51817Y-152763D01*
X53564Y-152471D01*
X55311Y-151013D01*
X56402Y-149263D01*
X56621Y-147513D01*
X56184Y-145472D01*
X54656Y-144013D01*
X53127Y-143430D01*
X51162D01*
G01X53127D02*
X54437Y-142555D01*
X55529Y-141097D01*
X55966Y-139347D01*
X55529Y-137596D01*
X54437Y-136138D01*
X52472Y-135263D01*
X50507Y-135555D01*
X48542Y-136722D01*
G01X64296Y-149263D02*
X65605Y-151305D01*
X67352Y-152471D01*
X69317Y-152763D01*
X71064Y-152471D01*
X72811Y-151013D01*
X73902Y-149263D01*
X74121Y-147513D01*
X73684Y-145472D01*
X72156Y-144013D01*
X70627Y-143430D01*
X68662D01*
G01X70627D02*
X71937Y-142555D01*
X73029Y-141097D01*
X73466Y-139347D01*
X73029Y-137596D01*
X71937Y-136138D01*
X69972Y-135263D01*
X68007Y-135555D01*
X66042Y-136722D01*
G01X-14018Y-107763D02*
Y-90263D01*
X-8778D01*
X-7031Y-91138D01*
X-5721Y-93180D01*
X-5284Y-95513D01*
X-5721Y-97846D01*
X-6813Y-99596D01*
X-8778Y-100472D01*
X-14018D01*
G01X12652Y-91722D02*
X11342Y-90846D01*
X9814Y-90263D01*
X8067D01*
X6102Y-91138D01*
X4574Y-92596D01*
X3482Y-94347D01*
X2609Y-97263D01*
X2390Y-99888D01*
X2827Y-102513D01*
X3482Y-104263D01*
X4792Y-106013D01*
X6321Y-107180D01*
X7849Y-107763D01*
X9377D01*
X10906Y-107180D01*
X12216Y-106305D01*
X13308Y-105139D01*
G01X27095Y-98430D02*
X27969Y-97555D01*
X28624Y-96097D01*
X29061Y-94054D01*
X28624Y-92305D01*
X27751Y-91138D01*
X26222Y-90263D01*
X20327D01*
Y-107763D01*
X27532D01*
X29061Y-106597D01*
X29934Y-104846D01*
X30371Y-102805D01*
X29934Y-100763D01*
X28624Y-99013D01*
X27095Y-98430D01*
X20327D01*
G01X36299Y-113596D02*
X49399D01*
G01X55327Y-107763D02*
Y-90263D01*
X65371Y-107763D01*
Y-90263D01*
G01X77849Y-107763D02*
X76102Y-107471D01*
X74574Y-106305D01*
X73264Y-104555D01*
X72390Y-102513D01*
X71954Y-100180D01*
Y-97846D01*
X72390Y-95513D01*
X73264Y-93471D01*
X74574Y-91722D01*
X76102Y-90555D01*
X77849Y-90263D01*
X79595Y-90555D01*
X81124Y-91722D01*
X82434Y-93471D01*
X83308Y-95513D01*
X83744Y-97846D01*
Y-100180D01*
X83308Y-102513D01*
X82434Y-104555D01*
X81124Y-106305D01*
X79595Y-107471D01*
X77849Y-107763D01*
G01X128690Y-90263D02*
X134149Y-107763D01*
X139608Y-90263D01*
G01X156016Y-107763D02*
X147282D01*
Y-90263D01*
X156016D01*
G01X152522Y-98721D02*
X147282D01*
G01X164782Y-107763D02*
Y-90263D01*
X170241D01*
X171987Y-91138D01*
X173079Y-92305D01*
X173516Y-94638D01*
X173079Y-96972D01*
X171769Y-98430D01*
X170241Y-99305D01*
X164782D01*
G01X170241D02*
X173516Y-107763D01*
G01X186649Y-108346D02*
X186212Y-108055D01*
Y-107471D01*
X186649Y-107180D01*
X187086Y-107471D01*
Y-108055D01*
X186649Y-108346D01*
G01X151649Y-152763D02*
Y-135263D01*
X149029Y-138763D01*
G01Y-152763D02*
X154269D01*
G01X163472D02*
Y-135263D01*
X169149Y-149846D01*
X174826Y-135263D01*
Y-152763D01*
G01X266599Y-135263D02*
Y-152763D01*
G01X261577Y-135263D02*
X271621D01*
G01X278422Y-152763D02*
Y-135263D01*
X284099Y-149846D01*
X289776Y-135263D01*
Y-152763D01*
G01X296140D02*
X301599Y-135263D01*
X307058Y-152763D01*
G01X305092Y-146638D02*
X298105D01*
G01X314514Y-150430D02*
X316261Y-151888D01*
X318226Y-152763D01*
X319972D01*
X321719Y-151888D01*
X323029Y-150430D01*
X323684Y-148388D01*
X323247Y-146347D01*
X322156Y-144596D01*
X320191Y-143430D01*
X317571Y-142846D01*
X316042Y-141680D01*
X315387Y-139638D01*
X315824Y-137596D01*
X316916Y-136138D01*
X318444Y-135263D01*
X319972D01*
X321501Y-135846D01*
X322811Y-137305D01*
G01X331796Y-152763D02*
Y-135263D01*
G01X340092D02*
X331796Y-146055D01*
G01X341402Y-152763D02*
X335507Y-141097D01*
G01X253482Y-90263D02*
Y-107763D01*
X262216D01*
G01X279279D02*
Y-96097D01*
G01Y-98138D02*
X278406Y-96972D01*
X277095Y-96388D01*
X275567Y-96097D01*
X274039Y-96680D01*
X272729Y-97846D01*
X271855Y-99596D01*
X271419Y-101930D01*
X271855Y-104263D01*
X272729Y-106013D01*
X274039Y-107180D01*
X275567Y-107763D01*
X277095Y-107471D01*
X278406Y-106597D01*
X279279Y-105430D01*
G01X288264Y-113013D02*
X289574Y-113596D01*
X291321Y-113013D01*
X292412Y-111847D01*
X293286Y-110388D01*
X294595Y-105722D01*
X297434Y-96097D01*
G01X290447D02*
X294595Y-105722D01*
G01X307074Y-99888D02*
X314061D01*
X313406Y-97846D01*
X312314Y-96680D01*
X310786Y-96097D01*
X309257Y-96388D01*
X307947Y-97263D01*
X307074Y-99305D01*
X306637Y-101055D01*
Y-102805D01*
X307074Y-104555D01*
X308166Y-106305D01*
X309476Y-107471D01*
X311004Y-107763D01*
X312532Y-107180D01*
X314061Y-105430D01*
G01X324792Y-107763D02*
Y-96097D01*
G01Y-98430D02*
X325884Y-97263D01*
X326976Y-96388D01*
X328504Y-96097D01*
X329595Y-96388D01*
X330906Y-97263D01*
G01X342074Y-105722D02*
X343166Y-106888D01*
X344694Y-107763D01*
X346004D01*
X347314Y-107180D01*
X348187Y-106305D01*
X348624Y-105139D01*
X348406Y-103388D01*
X347532Y-102513D01*
X343602Y-100763D01*
X342729Y-98721D01*
X343166Y-97263D01*
X344039Y-96388D01*
X345349Y-96097D01*
X346659Y-96388D01*
X347969Y-97263D01*
G01X404346Y-107763D02*
Y-90263D01*
X408712D01*
X410459Y-91138D01*
X411769Y-92305D01*
X412861Y-94054D01*
X413734Y-96097D01*
X413952Y-99013D01*
X413734Y-101930D01*
X412861Y-103972D01*
X411769Y-105722D01*
X410459Y-106888D01*
X408712Y-107763D01*
X404346D01*
G01X423374Y-99888D02*
X430361D01*
X429706Y-97846D01*
X428614Y-96680D01*
X427086Y-96097D01*
X425557Y-96388D01*
X424247Y-97263D01*
X423374Y-99305D01*
X422937Y-101055D01*
Y-102805D01*
X423374Y-104555D01*
X424466Y-106305D01*
X425776Y-107471D01*
X427304Y-107763D01*
X428832Y-107180D01*
X430361Y-105430D01*
G01X440874Y-105722D02*
X441966Y-106888D01*
X443494Y-107763D01*
X444804D01*
X446114Y-107180D01*
X446987Y-106305D01*
X447424Y-105139D01*
X447206Y-103388D01*
X446332Y-102513D01*
X442402Y-100763D01*
X441529Y-98721D01*
X441966Y-97263D01*
X442839Y-96388D01*
X444149Y-96097D01*
X445459Y-96388D01*
X446769Y-97263D01*
G01X461649Y-96097D02*
Y-107763D01*
G01Y-91430D02*
X461212Y-91138D01*
Y-90555D01*
X461649Y-90263D01*
X462086Y-90555D01*
Y-91138D01*
X461649Y-91430D01*
G01X476092Y-112138D02*
X477621Y-113305D01*
X479367Y-113596D01*
X480895Y-113305D01*
X482206Y-111847D01*
X483079Y-109805D01*
Y-96097D01*
G01Y-98430D02*
X482206Y-97263D01*
X480895Y-96388D01*
X479367Y-96097D01*
X477621Y-96680D01*
X476529Y-97846D01*
X475655Y-99888D01*
X475219Y-101930D01*
X475437Y-103680D01*
X476311Y-105722D01*
X477621Y-107180D01*
X479367Y-107763D01*
X480677Y-107471D01*
X482206Y-106305D01*
X483079Y-105139D01*
G01X492937Y-107763D02*
Y-96097D01*
G01Y-99013D02*
X493811Y-97555D01*
X495121Y-96388D01*
X496867Y-96097D01*
X498395Y-96388D01*
X499706Y-97555D01*
X500361Y-99596D01*
Y-107763D01*
G01X510874Y-99888D02*
X517861D01*
X517206Y-97846D01*
X516114Y-96680D01*
X514586Y-96097D01*
X513057Y-96388D01*
X511747Y-97263D01*
X510874Y-99305D01*
X510437Y-101055D01*
Y-102805D01*
X510874Y-104555D01*
X511966Y-106305D01*
X513276Y-107471D01*
X514804Y-107763D01*
X516332Y-107180D01*
X517861Y-105430D01*
G01X528592Y-107763D02*
Y-96097D01*
G01Y-98430D02*
X529684Y-97263D01*
X530776Y-96388D01*
X532304Y-96097D01*
X533395Y-96388D01*
X534706Y-97263D01*
G01X448096Y-152763D02*
Y-135263D01*
X452462D01*
X454209Y-136138D01*
X455519Y-137305D01*
X456611Y-139054D01*
X457484Y-141097D01*
X457702Y-144013D01*
X457484Y-146930D01*
X456611Y-148972D01*
X455519Y-150722D01*
X454209Y-151888D01*
X452462Y-152763D01*
X448096D01*
G01X470399Y-141097D02*
Y-152763D01*
G01Y-136430D02*
X469962Y-136138D01*
Y-135555D01*
X470399Y-135263D01*
X470836Y-135555D01*
Y-136138D01*
X470399Y-136430D01*
G01X487899Y-152763D02*
X486589Y-152471D01*
X485279Y-151305D01*
X484405Y-149263D01*
X483969Y-146930D01*
X484405Y-144596D01*
X485279Y-142555D01*
X486589Y-141388D01*
X487899Y-141097D01*
X489209Y-141388D01*
X490519Y-142555D01*
X491392Y-144596D01*
X491611Y-146930D01*
X491392Y-149263D01*
X490519Y-151305D01*
X489209Y-152471D01*
X487899Y-152763D01*
G01X575349D02*
Y-135263D01*
X572729Y-138763D01*
G01Y-152763D02*
X577969D01*
G01X588701Y-138180D02*
X590011Y-136430D01*
X591539Y-135555D01*
X593286Y-135263D01*
X595469Y-135846D01*
X596997Y-137305D01*
X597434Y-139054D01*
X597216Y-140805D01*
X596342Y-142263D01*
X591976Y-145180D01*
X590011Y-147221D01*
X588701Y-150139D01*
X588264Y-152763D01*
X597434D01*
G01X606419Y-153346D02*
X614279Y-135263D01*
G01X627849D02*
X626102Y-135846D01*
X624792Y-137305D01*
X623919Y-139054D01*
X623264Y-141388D01*
X623046Y-144013D01*
X623264Y-146638D01*
X623919Y-148972D01*
X624792Y-150722D01*
X626102Y-152180D01*
X627849Y-152763D01*
X629595Y-152180D01*
X630906Y-150722D01*
X631779Y-148972D01*
X632434Y-146638D01*
X632652Y-144013D01*
X632434Y-141388D01*
X631779Y-139054D01*
X630906Y-137305D01*
X629595Y-135846D01*
X627849Y-135263D01*
G01X644912Y-152763D02*
X645349Y-148972D01*
X646004Y-145763D01*
X646877Y-142846D01*
X647969Y-139638D01*
X649716Y-135263D01*
X640982D01*
G01X658919Y-153346D02*
X666779Y-135263D01*
G01X676201Y-138180D02*
X677511Y-136430D01*
X679039Y-135555D01*
X680786Y-135263D01*
X682969Y-135846D01*
X684497Y-137305D01*
X684934Y-139054D01*
X684716Y-140805D01*
X683842Y-142263D01*
X679476Y-145180D01*
X677511Y-147221D01*
X676201Y-150139D01*
X675764Y-152763D01*
X684934D01*
G01X697849Y-135263D02*
X696102Y-135846D01*
X694792Y-137305D01*
X693919Y-139054D01*
X693264Y-141388D01*
X693046Y-144013D01*
X693264Y-146638D01*
X693919Y-148972D01*
X694792Y-150722D01*
X696102Y-152180D01*
X697849Y-152763D01*
X699595Y-152180D01*
X700906Y-150722D01*
X701779Y-148972D01*
X702434Y-146638D01*
X702652Y-144013D01*
X702434Y-141388D01*
X701779Y-139054D01*
X700906Y-137305D01*
X699595Y-135846D01*
X697849Y-135263D01*
G01X715349Y-152763D02*
Y-135263D01*
X712729Y-138763D01*
G01Y-152763D02*
X717969D01*
G01X728701Y-138180D02*
X730011Y-136430D01*
X731539Y-135555D01*
X733286Y-135263D01*
X735469Y-135846D01*
X736997Y-137305D01*
X737434Y-139054D01*
X737216Y-140805D01*
X736342Y-142263D01*
X731976Y-145180D01*
X730011Y-147221D01*
X728701Y-150139D01*
X728264Y-152763D01*
X737434D01*
G01X623046Y-107763D02*
Y-90263D01*
X627412D01*
X629159Y-91138D01*
X630469Y-92305D01*
X631561Y-94054D01*
X632434Y-96097D01*
X632652Y-99013D01*
X632434Y-101930D01*
X631561Y-103972D01*
X630469Y-105722D01*
X629159Y-106888D01*
X627412Y-107763D01*
X623046D01*
G01X649279D02*
Y-96097D01*
G01Y-98138D02*
X648406Y-96972D01*
X647095Y-96388D01*
X645567Y-96097D01*
X644039Y-96680D01*
X642729Y-97846D01*
X641855Y-99596D01*
X641419Y-101930D01*
X641855Y-104263D01*
X642729Y-106013D01*
X644039Y-107180D01*
X645567Y-107763D01*
X647095Y-107471D01*
X648406Y-106597D01*
X649279Y-105430D01*
G01X662849Y-90263D02*
Y-107763D01*
G01X659792Y-96097D02*
X665906D01*
G01X677074Y-99888D02*
X684061D01*
X683406Y-97846D01*
X682314Y-96680D01*
X680786Y-96097D01*
X679257Y-96388D01*
X677947Y-97263D01*
X677074Y-99305D01*
X676637Y-101055D01*
Y-102805D01*
X677074Y-104555D01*
X678166Y-106305D01*
X679476Y-107471D01*
X681004Y-107763D01*
X682532Y-107180D01*
X684061Y-105430D01*
G54D78*
X117000Y1452000D03*
G54D69*
X102835Y640154D03*
Y638189D03*
Y636219D03*
Y634249D03*
Y632284D03*
Y630314D03*
Y628344D03*
Y626374D03*
Y624409D03*
Y622439D03*
Y620469D03*
Y618504D03*
X136235D03*
Y620469D03*
Y622439D03*
Y624409D03*
Y626374D03*
Y628344D03*
Y630314D03*
Y632284D03*
Y634249D03*
Y636219D03*
Y638189D03*
Y640154D03*
G54D79*
X150000Y64500D03*
X152500Y1906000D03*
M02*
